# S9S_MB_2U (Grand Teton) — schematic netlist excerpt (pin names and nets, part order shuffled) for the footprints in the layout excerpt that follows; sources: Cadence DE-HDL packaged netlist, KiCad conversion of 03242023_DA0F0TMBIJ0_F0T_Motherboard_J_brd_V01_OCP.brd

C1030  Q_CAP  22UF 4V 20% X6S  pkg C0402  page 74 : A = PVCCIN_CPU0 ; B = GND

X8  TP_TDR_4P_FTS  TP_TDR_4P_DIP EMPTY  pkg TH  page 309
  S1  = TDR_DIFF_85_IN1_DN
  P1  = T1_GND
  P2  = T1_GND
  S2  = TDR_DIFF_85_IN1_DP

(kicad_pcb
	(version 20260206)
	(generator "pcbnew")
	(generator_version "10.0")
	(general
		(thickness 1.6)
		(legacy_teardrops no)
	)
	(paper "A4")
	(title_block
		(title "03242023_DA0F0TMBIJ0_F0T_Motherboard_J_brd_V01_OCP.brd")
		(comment 1 "Grand Teton / footprints 3524-3525 of 6105")
	)
	(layers
		(0 "F.Cu" signal "TOP")
		(4 "In1.Cu" signal "GND")
		(6 "In2.Cu" signal "IN1")
		(8 "In3.Cu" signal "GND1")
		(10 "In4.Cu" signal "IN2")
		(12 "In5.Cu" signal "GND2")
		(14 "In6.Cu" signal "IN3")
		(16 "In7.Cu" signal "GND3")
		(18 "In8.Cu" signal "VCC")
		(20 "In9.Cu" signal "VCC1")
		(22 "In10.Cu" signal "GND4")
		(24 "In11.Cu" signal "IN4")
		(26 "In12.Cu" signal "GND5")
		(28 "In13.Cu" signal "IN5")
		(30 "In14.Cu" signal "GND6")
		(32 "In15.Cu" signal "IN6")
		(34 "In16.Cu" signal "GND7")
		(2 "B.Cu" signal "BOTTOM")
		(9 "F.Adhes" user "F.Adhesive")
		(11 "B.Adhes" user "B.Adhesive")
		(13 "F.Paste" user "Package Geometry/Pastemask Top")
		(15 "B.Paste" user "Package Geometry/Pastemask Bottom")
		(5 "F.SilkS" user "Ref Des/Silkscreen Top")
		(7 "B.SilkS" user "Ref Des/Silkscreen Bottom")
		(1 "F.Mask" user "Board Geometry/Soldermask Top")
		(3 "B.Mask" user "Board Geometry/Soldermask Bottom")
		(17 "Dwgs.User" user "User.Drawings")
		(19 "Cmts.User" user "User.Comments")
		(21 "Eco1.User" user "User.Eco1")
		(23 "Eco2.User" user "User.Eco2")
		(25 "Edge.Cuts" user "Board Geometry/Outline")
		(27 "Margin" user)
		(31 "F.CrtYd" user "Package Geometry/Place Bound Top")
		(29 "B.CrtYd" user "Package Geometry/Place Bound Bottom")
		(35 "F.Fab" user "Ref Des/Assembly Top")
		(33 "B.Fab" user "Ref Des/Assembly Bottom")
	)
	(footprint ""
		(layer "F.Cu")
		(at 352.301048 -249.320304 -90)
		(property "Reference" "C1030"
			(at 0 0 270)
			(layer "F.SilkS")
			(hide yes)
			(effects
				(font
					(size 1.27 1.27)
				)
			)
		)
		(property "Value" ""
			(at 0 0 270)
			(layer "F.Fab")
			(effects
				(font
					(size 1.27 1.27)
				)
			)
		)
		(duplicate_pad_numbers_are_jumpers no)
		(fp_line
			(start -0.7874 0.4064)
			(end -0.7874 -0.4064)
			(stroke
				(width 0.1524)
				(type default)
			)
			(layer "F.SilkS")
		)
		(fp_line
			(start 0.7874 0.4064)
			(end -0.7874 0.4064)
			(stroke
				(width 0.1524)
				(type default)
			)
			(layer "F.SilkS")
		)
		(fp_line
			(start -0.7874 -0.4064)
			(end 0.7874 -0.4064)
			(stroke
				(width 0.1524)
				(type default)
			)
			(layer "F.SilkS")
		)
		(fp_line
			(start 0.7874 -0.4064)
			(end 0.7874 0.4064)
			(stroke
				(width 0.1524)
				(type default)
			)
			(layer "F.SilkS")
		)
		(fp_line
			(start -0.67945 0.3048)
			(end -0.67945 -0.305054)
			(stroke
				(width 0.1)
				(type default)
			)
			(layer "F.Fab")
		)
		(fp_line
			(start -0.12065 0.3048)
			(end -0.67945 0.3048)
			(stroke
				(width 0.1)
				(type default)
			)
			(layer "F.Fab")
		)
		(fp_line
			(start 0.120396 0.3048)
			(end 0.120396 0.2794)
			(stroke
				(width 0.1)
				(type default)
			)
			(layer "F.Fab")
		)
		(fp_line
			(start 0.67945 0.3048)
			(end 0.120396 0.3048)
			(stroke
				(width 0.1)
				(type default)
			)
			(layer "F.Fab")
		)
		(fp_line
			(start -0.12065 0.2794)
			(end -0.12065 0.3048)
			(stroke
				(width 0.1)
				(type default)
			)
			(layer "F.Fab")
		)
		(fp_line
			(start 0.120396 0.2794)
			(end -0.12065 0.2794)
			(stroke
				(width 0.1)
				(type default)
			)
			(layer "F.Fab")
		)
		(fp_line
			(start -0.12065 -0.2794)
			(end 0.12065 -0.2794)
			(stroke
				(width 0.1)
				(type default)
			)
			(layer "F.Fab")
		)
		(fp_line
			(start 0.12065 -0.2794)
			(end 0.12065 -0.3048)
			(stroke
				(width 0.1)
				(type default)
			)
			(layer "F.Fab")
		)
		(fp_line
			(start 0.12065 -0.3048)
			(end 0.67945 -0.3048)
			(stroke
				(width 0.1)
				(type default)
			)
			(layer "F.Fab")
		)
		(fp_line
			(start 0.67945 -0.3048)
			(end 0.67945 0.3048)
			(stroke
				(width 0.1)
				(type default)
			)
			(layer "F.Fab")
		)
		(fp_line
			(start -0.67945 -0.305054)
			(end -0.12065 -0.305054)
			(stroke
				(width 0.1)
				(type default)
			)
			(layer "F.Fab")
		)
		(fp_line
			(start -0.12065 -0.305054)
			(end -0.12065 -0.2794)
			(stroke
				(width 0.1)
				(type default)
			)
			(layer "F.Fab")
		)
		(pad "1" smd circle
			(at -0.40005 0 270)
			(size 0 0)
			(layers "F.Cu" "F.Mask" "F.Paste")
			(net "PVCCIN_CPU0")
		)
		(pad "2" smd circle
			(at 0.40005 0 270)
			(size 0 0)
			(layers "F.Cu" "F.Mask" "F.Paste")
			(net "GND")
		)
	)
	(footprint ""
		(layer "F.Cu")
		(at 514.718808 -303.6316 90)
		(property "Reference" "X8"
			(at -2.734056 3.043682 90)
			(unlocked yes)
			(layer "F.SilkS")
			(effects
				(font
					(size 0.7874 0.5842)
					(thickness 0.1524)
				)
				(justify left)
			)
		)
		(property "Value" ""
			(at 0 0 90)
			(layer "F.Fab")
			(effects
				(font
					(size 1.27 1.27)
				)
			)
		)
		(property "Device Type" "TP_TDR_4P_FTS_MPKT4_H025P0200_I"
			(at 1.30175 1.27 180)
			(unlocked yes)
			(layer "F.Fab")
			(hide yes)
			(effects
				(font
					(size 0.635 0.4064)
					(thickness 0.1524)
				)
			)
		)
		(property "User Part Number" "TP15"
			(at 1.30175 1.27 180)
			(unlocked yes)
			(layer "Cmts.User")
			(hide yes)
			(effects
				(font
					(size 0.635 0.4064)
					(thickness 0.1524)
				)
			)
		)
		(duplicate_pad_numbers_are_jumpers no)
		(fp_line
			(start 2.54 -1.27)
			(end 0 -1.27)
			(stroke
				(width 0.1524)
				(type default)
			)
			(layer "F.SilkS")
		)
		(fp_line
			(start 0 -1.27)
			(end 0 -0.635)
			(stroke
				(width 0.1524)
				(type default)
			)
			(layer "F.SilkS")
		)
		(fp_line
			(start 2.54 -1.1303)
			(end 2.54 -1.27)
			(stroke
				(width 0.1524)
				(type default)
			)
			(layer "F.SilkS")
		)
		(fp_line
			(start 0 0.635)
			(end 0 1.905)
			(stroke
				(width 0.1524)
				(type default)
			)
			(layer "F.SilkS")
		)
		(fp_line
			(start 2.54 1.4097)
			(end 2.54 1.1303)
			(stroke
				(width 0.1524)
				(type default)
			)
			(layer "F.SilkS")
		)
		(fp_line
			(start 0 3.175)
			(end 0 3.81)
			(stroke
				(width 0.1524)
				(type default)
			)
			(layer "F.SilkS")
		)
		(fp_line
			(start 2.54 3.81)
			(end 2.54 3.6703)
			(stroke
				(width 0.1524)
				(type default)
			)
			(layer "F.SilkS")
		)
		(fp_line
			(start 0 3.81)
			(end 2.54 3.81)
			(stroke
				(width 0.1524)
				(type default)
			)
			(layer "F.SilkS")
		)
		(fp_poly
			(pts
				(xy -0.761746 0) (xy -2.285746 0.762) (xy -2.285746 -0.762)
			)
			(stroke
				(width 0)
				(type default)
			)
			(fill yes)
			(layer "F.SilkS")
		)
		(fp_line
			(start 2.54 -1.27)
			(end 0 -1.27)
			(stroke
				(width 0.1)
				(type default)
			)
			(layer "F.Fab")
		)
		(fp_line
			(start 0 -1.27)
			(end 0 3.81)
			(stroke
				(width 0.1)
				(type default)
			)
			(layer "F.Fab")
		)
		(fp_line
			(start 2.54 3.81)
			(end 2.54 -1.27)
			(stroke
				(width 0.1)
				(type default)
			)
			(layer "F.Fab")
		)
		(fp_line
			(start 0 3.81)
			(end 2.54 3.81)
			(stroke
				(width 0.1)
				(type default)
			)
			(layer "F.Fab")
		)
		(fp_poly
			(pts
				(xy -0.761746 0) (xy -2.285746 -0.762) (xy -2.285746 0.762)
			)
			(stroke
				(width 0)
				(type default)
			)
			(fill yes)
			(layer "F.Fab")
		)
		(pad "1" thru_hole circle
			(at 0 0 90)
			(size 1.0033 1.0033)
			(drill 0.249936)
			(layers "*.Cu" "*.Mask")
			(remove_unused_layers no)
			(net "TDR_DIFF_85_IN1_DN")
			(clearance 0.10795)
			(thermal_gap 0.10795)
			(padstack
				(mode front_inner_back)
				(layer "Inner"
					(shape circle)
					(size 0.8001 0.8001)
					(clearance 0.1524)
				)
				(layer "B.Cu"
					(shape circle)
					(size 1.0033 1.0033)
					(clearance 0.10795)
				)
			)
		)
		(pad "2" thru_hole circle
			(at 2.54 0 90)
			(size 1.9939 1.9939)
			(drill 0.249936)
			(layers "*.Cu" "*.Mask")
			(remove_unused_layers no)
			(net "T1_GND")
			(clearance 0.10795)
			(thermal_gap 0.10795)
			(padstack
				(mode front_inner_back)
				(layer "Inner"
					(shape circle)
					(size 0.8001 0.8001)
					(clearance 0.1524)
				)
				(layer "B.Cu"
					(shape circle)
					(size 1.9939 1.9939)
					(clearance 0.10795)
				)
			)
		)
		(pad "3" thru_hole circle
			(at 2.54 2.54 90)
			(size 1.9939 1.9939)
			(drill 0.249936)
			(layers "*.Cu" "*.Mask")
			(remove_unused_layers no)
			(net "T1_GND")
			(clearance 0.10795)
			(thermal_gap 0.10795)
			(padstack
				(mode front_inner_back)
				(layer "Inner"
					(shape circle)
					(size 0.8001 0.8001)
					(clearance 0.1524)
				)
				(layer "B.Cu"
					(shape circle)
					(size 1.9939 1.9939)
					(clearance 0.10795)
				)
			)
		)
		(pad "4" thru_hole circle
			(at 0 2.54 90)
			(size 1.0033 1.0033)
			(drill 0.249936)
			(layers "*.Cu" "*.Mask")
			(remove_unused_layers no)
			(net "TDR_DIFF_85_IN1_DP")
			(clearance 0.10795)
			(thermal_gap 0.10795)
			(padstack
				(mode front_inner_back)
				(layer "Inner"
					(shape circle)
					(size 0.8001 0.8001)
					(clearance 0.1524)
				)
				(layer "B.Cu"
					(shape circle)
					(size 1.0033 1.0033)
					(clearance 0.10795)
				)
			)
		)
	)
)
